# SCM (Grand Teton) — schematic netlist excerpt (pin names and nets, part order shuffled) for the footprints in the layout excerpt that follows; sources: Cadence DE-HDL packaged netlist, KiCad conversion of 12092022_DA0F0TMDCD0_F0T_Management_Board_D_brd_V3_OCP.brd

R245  Q_RES  1.8K 1% CHIP  pkg 0402LF  page 27 : A = P3V3_AUX ; B = SMB_BMC_MM1_SDA
R123  Q_RES  33.2 1% CHIP  pkg 0402LF  page 34 : A = FM_TPM_PRSNT_1_N ; B = FM_TPM_PRSNT_1_R_N

(kicad_pcb
	(version 20260206)
	(generator "pcbnew")
	(generator_version "10.0")
	(general
		(thickness 1.6)
		(legacy_teardrops no)
	)
	(paper "A4")
	(title_block
		(title "12092022_DA0F0TMDCD0_F0T_Management_Board_D_brd_V3_OCP.brd")
		(comment 1 "Grand Teton / footprints 299-300 of 1440")
	)
	(layers
		(0 "F.Cu" signal "TOP")
		(4 "In1.Cu" signal "GND")
		(6 "In2.Cu" signal "IN1")
		(8 "In3.Cu" signal "GND1")
		(10 "In4.Cu" signal "IN2")
		(12 "In5.Cu" signal "VCC")
		(14 "In6.Cu" signal "VCC1")
		(16 "In7.Cu" signal "IN3")
		(18 "In8.Cu" signal "GND2")
		(20 "In9.Cu" signal "IN4")
		(22 "In10.Cu" signal "GND3")
		(2 "B.Cu" signal "BOTTOM")
		(9 "F.Adhes" user "F.Adhesive")
		(11 "B.Adhes" user "B.Adhesive")
		(13 "F.Paste" user "Package Geometry/Pastemask Top")
		(15 "B.Paste" user "Package Geometry/Pastemask Bottom")
		(5 "F.SilkS" user "Ref Des/Silkscreen Top")
		(7 "B.SilkS" user "Ref Des/Silkscreen Bottom")
		(1 "F.Mask" user "Board Geometry/Soldermask Top")
		(3 "B.Mask" user "Board Geometry/Soldermask Bottom")
		(17 "Dwgs.User" user "User.Drawings")
		(19 "Cmts.User" user "User.Comments")
		(21 "Eco1.User" user "User.Eco1")
		(23 "Eco2.User" user "User.Eco2")
		(25 "Edge.Cuts" user "Board Geometry/Outline")
		(27 "Margin" user)
		(31 "F.CrtYd" user "Package Geometry/Place Bound Top")
		(29 "B.CrtYd" user "Package Geometry/Place Bound Bottom")
		(35 "F.Fab" user "Ref Des/Assembly Top")
		(33 "B.Fab" user "Ref Des/Assembly Bottom")
	)
	(footprint ""
		(layer "F.Cu")
		(at 48.6156 -30.867604 90)
		(property "Reference" "R245"
			(at 0 0 90)
			(layer "F.SilkS")
			(hide yes)
			(effects
				(font
					(size 1.27 1.27)
				)
			)
		)
		(property "Value" ""
			(at 0 0 90)
			(layer "F.Fab")
			(effects
				(font
					(size 1.27 1.27)
				)
			)
		)
		(duplicate_pad_numbers_are_jumpers no)
		(fp_line
			(start 0.7874 -0.4064)
			(end 0.7874 0.4064)
			(stroke
				(width 0.1524)
				(type default)
			)
			(layer "F.SilkS")
		)
		(fp_line
			(start -0.7874 -0.4064)
			(end 0.7874 -0.4064)
			(stroke
				(width 0.1524)
				(type default)
			)
			(layer "F.SilkS")
		)
		(fp_line
			(start 0.7874 0.4064)
			(end -0.7874 0.4064)
			(stroke
				(width 0.1524)
				(type default)
			)
			(layer "F.SilkS")
		)
		(fp_line
			(start -0.7874 0.4064)
			(end -0.7874 -0.4064)
			(stroke
				(width 0.1524)
				(type default)
			)
			(layer "F.SilkS")
		)
		(fp_line
			(start -0.12065 -0.305054)
			(end -0.12065 -0.2794)
			(stroke
				(width 0.1)
				(type default)
			)
			(layer "F.Fab")
		)
		(fp_line
			(start -0.67945 -0.305054)
			(end -0.12065 -0.305054)
			(stroke
				(width 0.1)
				(type default)
			)
			(layer "F.Fab")
		)
		(fp_line
			(start 0.67945 -0.3048)
			(end 0.67945 0.3048)
			(stroke
				(width 0.1)
				(type default)
			)
			(layer "F.Fab")
		)
		(fp_line
			(start 0.12065 -0.3048)
			(end 0.67945 -0.3048)
			(stroke
				(width 0.1)
				(type default)
			)
			(layer "F.Fab")
		)
		(fp_line
			(start 0.12065 -0.2794)
			(end 0.12065 -0.3048)
			(stroke
				(width 0.1)
				(type default)
			)
			(layer "F.Fab")
		)
		(fp_line
			(start -0.12065 -0.2794)
			(end 0.12065 -0.2794)
			(stroke
				(width 0.1)
				(type default)
			)
			(layer "F.Fab")
		)
		(fp_line
			(start 0.120396 0.2794)
			(end -0.12065 0.2794)
			(stroke
				(width 0.1)
				(type default)
			)
			(layer "F.Fab")
		)
		(fp_line
			(start -0.12065 0.2794)
			(end -0.12065 0.3048)
			(stroke
				(width 0.1)
				(type default)
			)
			(layer "F.Fab")
		)
		(fp_line
			(start 0.67945 0.3048)
			(end 0.120396 0.3048)
			(stroke
				(width 0.1)
				(type default)
			)
			(layer "F.Fab")
		)
		(fp_line
			(start 0.120396 0.3048)
			(end 0.120396 0.2794)
			(stroke
				(width 0.1)
				(type default)
			)
			(layer "F.Fab")
		)
		(fp_line
			(start -0.12065 0.3048)
			(end -0.67945 0.3048)
			(stroke
				(width 0.1)
				(type default)
			)
			(layer "F.Fab")
		)
		(fp_line
			(start -0.67945 0.3048)
			(end -0.67945 -0.305054)
			(stroke
				(width 0.1)
				(type default)
			)
			(layer "F.Fab")
		)
		(pad "1" smd circle
			(at -0.40005 0 90)
			(size 0 0)
			(layers "F.Cu" "F.Mask" "F.Paste")
			(net "P3V3_AUX")
		)
		(pad "2" smd circle
			(at 0.40005 0 90)
			(size 0 0)
			(layers "F.Cu" "F.Mask" "F.Paste")
			(net "SMB_BMC_MM1_SDA")
		)
	)
	(footprint ""
		(layer "F.Cu")
		(at 24.892 -83.7438 90)
		(property "Reference" "R123"
			(at 0 0 90)
			(layer "F.SilkS")
			(hide yes)
			(effects
				(font
					(size 1.27 1.27)
				)
			)
		)
		(property "Value" ""
			(at 0 0 90)
			(layer "F.Fab")
			(effects
				(font
					(size 1.27 1.27)
				)
			)
		)
		(duplicate_pad_numbers_are_jumpers no)
		(fp_line
			(start 0.7874 -0.4064)
			(end 0.7874 0.4064)
			(stroke
				(width 0.1524)
				(type default)
			)
			(layer "F.SilkS")
		)
		(fp_line
			(start -0.7874 -0.4064)
			(end 0.7874 -0.4064)
			(stroke
				(width 0.1524)
				(type default)
			)
			(layer "F.SilkS")
		)
		(fp_line
			(start 0.7874 0.4064)
			(end -0.7874 0.4064)
			(stroke
				(width 0.1524)
				(type default)
			)
			(layer "F.SilkS")
		)
		(fp_line
			(start -0.7874 0.4064)
			(end -0.7874 -0.4064)
			(stroke
				(width 0.1524)
				(type default)
			)
			(layer "F.SilkS")
		)
		(fp_line
			(start -0.12065 -0.305054)
			(end -0.12065 -0.2794)
			(stroke
				(width 0.1)
				(type default)
			)
			(layer "F.Fab")
		)
		(fp_line
			(start -0.67945 -0.305054)
			(end -0.12065 -0.305054)
			(stroke
				(width 0.1)
				(type default)
			)
			(layer "F.Fab")
		)
		(fp_line
			(start 0.67945 -0.3048)
			(end 0.67945 0.3048)
			(stroke
				(width 0.1)
				(type default)
			)
			(layer "F.Fab")
		)
		(fp_line
			(start 0.12065 -0.3048)
			(end 0.67945 -0.3048)
			(stroke
				(width 0.1)
				(type default)
			)
			(layer "F.Fab")
		)
		(fp_line
			(start 0.12065 -0.2794)
			(end 0.12065 -0.3048)
			(stroke
				(width 0.1)
				(type default)
			)
			(layer "F.Fab")
		)
		(fp_line
			(start -0.12065 -0.2794)
			(end 0.12065 -0.2794)
			(stroke
				(width 0.1)
				(type default)
			)
			(layer "F.Fab")
		)
		(fp_line
			(start 0.120396 0.2794)
			(end -0.12065 0.2794)
			(stroke
				(width 0.1)
				(type default)
			)
			(layer "F.Fab")
		)
		(fp_line
			(start -0.12065 0.2794)
			(end -0.12065 0.3048)
			(stroke
				(width 0.1)
				(type default)
			)
			(layer "F.Fab")
		)
		(fp_line
			(start 0.67945 0.3048)
			(end 0.120396 0.3048)
			(stroke
				(width 0.1)
				(type default)
			)
			(layer "F.Fab")
		)
		(fp_line
			(start 0.120396 0.3048)
			(end 0.120396 0.2794)
			(stroke
				(width 0.1)
				(type default)
			)
			(layer "F.Fab")
		)
		(fp_line
			(start -0.12065 0.3048)
			(end -0.67945 0.3048)
			(stroke
				(width 0.1)
				(type default)
			)
			(layer "F.Fab")
		)
		(fp_line
			(start -0.67945 0.3048)
			(end -0.67945 -0.305054)
			(stroke
				(width 0.1)
				(type default)
			)
			(layer "F.Fab")
		)
		(pad "1" smd circle
			(at -0.40005 0 90)
			(size 0 0)
			(layers "F.Cu" "F.Mask" "F.Paste")
			(net "FM_TPM_PRSNT_1_N")
		)
		(pad "2" smd circle
			(at 0.40005 0 90)
			(size 0 0)
			(layers "F.Cu" "F.Mask" "F.Paste")
			(net "FM_TPM_PRSNT_1_R_N")
		)
	)
)
